# T6G (Grand Teton) — schematic netlist excerpt (pin names and nets, part order shuffled) for the footprints in the layout excerpt that follows; sources: Cadence DE-HDL packaged netlist, KiCad conversion of 04192023_DAF0TMB3IC0_F0TG_MB_C_brd_V02_OCP.brd

PC185_4  Q_CAP  22UF 16V 20% X6S  pkg C0805  page 206 : A = SW_P12V_AUX_PVDDIO_P0_FLT ; B = GND
C170  Q_CAP  10UF 25V 10% X6S  pkg C0805  page 97 : A = P12V_MEM_CPU0 ; B = GND
R6092  Q_RES  0 5% CHIP  pkg 0402LF  page 85 : A = SCM_SYS_PWROK_R ; B = SCM_SYS_PWROK_R1

(kicad_pcb
	(version 20260206)
	(generator "pcbnew")
	(generator_version "10.0")
	(general
		(thickness 1.6)
		(legacy_teardrops no)
	)
	(paper "A4")
	(title_block
		(title "04192023_DAF0TMB3IC0_F0TG_MB_C_brd_V02_OCP.brd")
		(comment 1 "Grand Teton / footprints 5991-5993 of 8354")
	)
	(layers
		(0 "F.Cu" signal "TOP")
		(4 "In1.Cu" signal "GND")
		(6 "In2.Cu" signal "IN1")
		(8 "In3.Cu" signal "GND1")
		(10 "In4.Cu" signal "IN2")
		(12 "In5.Cu" signal "GND2")
		(14 "In6.Cu" signal "IN3")
		(16 "In7.Cu" signal "GND3")
		(18 "In8.Cu" signal "VCC")
		(20 "In9.Cu" signal "VCC1")
		(22 "In10.Cu" signal "GND4")
		(24 "In11.Cu" signal "IN4")
		(26 "In12.Cu" signal "GND5")
		(28 "In13.Cu" signal "IN5")
		(30 "In14.Cu" signal "GND6")
		(32 "In15.Cu" signal "IN6")
		(34 "In16.Cu" signal "GND7")
		(2 "B.Cu" signal "BOTTOM")
		(9 "F.Adhes" user "F.Adhesive")
		(11 "B.Adhes" user "B.Adhesive")
		(13 "F.Paste" user "Package Geometry/Pastemask Top")
		(15 "B.Paste" user "Package Geometry/Pastemask Bottom")
		(5 "F.SilkS" user "Ref Des/Silkscreen Top")
		(7 "B.SilkS" user "Ref Des/Silkscreen Bottom")
		(1 "F.Mask" user "Board Geometry/Soldermask Top")
		(3 "B.Mask" user "Board Geometry/Soldermask Bottom")
		(17 "Dwgs.User" user "User.Drawings")
		(19 "Cmts.User" user "User.Comments")
		(21 "Eco1.User" user "User.Eco1")
		(23 "Eco2.User" user "User.Eco2")
		(25 "Edge.Cuts" user "Board Geometry/Outline")
		(27 "Margin" user)
		(31 "F.CrtYd" user "Package Geometry/Place Bound Top")
		(29 "B.CrtYd" user "Package Geometry/Place Bound Bottom")
		(35 "F.Fab" user "Ref Des/Assembly Top")
		(33 "B.Fab" user "Ref Des/Assembly Bottom")
	)
	(footprint ""
		(layer "B.Cu")
		(at 164.062918 -119.336058)
		(property "Reference" "R6092"
			(at 0 0 0)
			(layer "B.SilkS")
			(hide yes)
			(effects
				(font
					(size 1.27 1.27)
				)
				(justify mirror)
			)
		)
		(property "Value" ""
			(at 0 0 0)
			(layer "B.Fab")
			(effects
				(font
					(size 1.27 1.27)
				)
				(justify mirror)
			)
		)
		(duplicate_pad_numbers_are_jumpers no)
		(fp_line
			(start -0.7874 -0.4064)
			(end -0.7874 0.4064)
			(stroke
				(width 0.1524)
				(type default)
			)
			(layer "B.SilkS")
		)
		(fp_line
			(start -0.7874 0.4064)
			(end 0.7874 0.4064)
			(stroke
				(width 0.1524)
				(type default)
			)
			(layer "B.SilkS")
		)
		(fp_line
			(start 0.7874 -0.4064)
			(end -0.7874 -0.4064)
			(stroke
				(width 0.1524)
				(type default)
			)
			(layer "B.SilkS")
		)
		(fp_line
			(start 0.7874 0.4064)
			(end 0.7874 -0.4064)
			(stroke
				(width 0.1524)
				(type default)
			)
			(layer "B.SilkS")
		)
		(fp_line
			(start -0.67945 -0.3048)
			(end -0.67945 0.3048)
			(stroke
				(width 0.1)
				(type default)
			)
			(layer "B.Fab")
		)
		(fp_line
			(start -0.67945 0.3048)
			(end -0.120396 0.3048)
			(stroke
				(width 0.1)
				(type default)
			)
			(layer "B.Fab")
		)
		(fp_line
			(start -0.12065 -0.3048)
			(end -0.67945 -0.3048)
			(stroke
				(width 0.1)
				(type default)
			)
			(layer "B.Fab")
		)
		(fp_line
			(start -0.12065 -0.2794)
			(end -0.12065 -0.3048)
			(stroke
				(width 0.1)
				(type default)
			)
			(layer "B.Fab")
		)
		(fp_line
			(start -0.120396 0.2794)
			(end 0.12065 0.2794)
			(stroke
				(width 0.1)
				(type default)
			)
			(layer "B.Fab")
		)
		(fp_line
			(start -0.120396 0.3048)
			(end -0.120396 0.2794)
			(stroke
				(width 0.1)
				(type default)
			)
			(layer "B.Fab")
		)
		(fp_line
			(start 0.12065 -0.305054)
			(end 0.12065 -0.2794)
			(stroke
				(width 0.1)
				(type default)
			)
			(layer "B.Fab")
		)
		(fp_line
			(start 0.12065 -0.2794)
			(end -0.12065 -0.2794)
			(stroke
				(width 0.1)
				(type default)
			)
			(layer "B.Fab")
		)
		(fp_line
			(start 0.12065 0.2794)
			(end 0.12065 0.3048)
			(stroke
				(width 0.1)
				(type default)
			)
			(layer "B.Fab")
		)
		(fp_line
			(start 0.12065 0.3048)
			(end 0.67945 0.3048)
			(stroke
				(width 0.1)
				(type default)
			)
			(layer "B.Fab")
		)
		(fp_line
			(start 0.67945 -0.305054)
			(end 0.12065 -0.305054)
			(stroke
				(width 0.1)
				(type default)
			)
			(layer "B.Fab")
		)
		(fp_line
			(start 0.67945 0.3048)
			(end 0.67945 -0.305054)
			(stroke
				(width 0.1)
				(type default)
			)
			(layer "B.Fab")
		)
		(pad "1" smd circle
			(at 0.40005 0 180)
			(size 0 0)
			(layers "B.Cu" "B.Mask" "B.Paste")
			(net "SCM_SYS_PWROK_R")
		)
		(pad "2" smd circle
			(at -0.40005 0 180)
			(size 0 0)
			(layers "B.Cu" "B.Mask" "B.Paste")
			(net "SCM_SYS_PWROK_R1")
		)
	)
	(footprint ""
		(layer "B.Cu")
		(at 454.188068 -192.660016)
		(property "Reference" "C170"
			(at 0 0 0)
			(layer "B.SilkS")
			(hide yes)
			(effects
				(font
					(size 1.27 1.27)
				)
				(justify mirror)
			)
		)
		(property "Value" ""
			(at 0 0 0)
			(layer "B.Fab")
			(effects
				(font
					(size 1.27 1.27)
				)
				(justify mirror)
			)
		)
		(duplicate_pad_numbers_are_jumpers no)
		(fp_line
			(start -1.524 -0.762)
			(end -1.524 0.762)
			(stroke
				(width 0.1524)
				(type default)
			)
			(layer "B.SilkS")
		)
		(fp_line
			(start -1.524 0.762)
			(end 1.524 0.762)
			(stroke
				(width 0.1524)
				(type default)
			)
			(layer "B.SilkS")
		)
		(fp_line
			(start 1.524 -0.762)
			(end -1.524 -0.762)
			(stroke
				(width 0.1524)
				(type default)
			)
			(layer "B.SilkS")
		)
		(fp_line
			(start 1.524 0.762)
			(end 1.524 -0.762)
			(stroke
				(width 0.1524)
				(type default)
			)
			(layer "B.SilkS")
		)
		(fp_line
			(start -1.1049 -0.724916)
			(end 1.1049 -0.724916)
			(stroke
				(width 0.1)
				(type default)
			)
			(layer "B.Fab")
		)
		(fp_line
			(start -1.1049 0.724916)
			(end -1.1049 -0.724916)
			(stroke
				(width 0.1)
				(type default)
			)
			(layer "B.Fab")
		)
		(fp_line
			(start 1.1049 -0.724916)
			(end 1.1049 0.724916)
			(stroke
				(width 0.1)
				(type default)
			)
			(layer "B.Fab")
		)
		(fp_line
			(start 1.1049 0.724916)
			(end -1.1049 0.724916)
			(stroke
				(width 0.1)
				(type default)
			)
			(layer "B.Fab")
		)
		(pad "1" smd rect
			(at 0.889 0)
			(size 1.016 1.27)
			(layers "B.Cu" "B.Mask" "B.Paste")
			(net "P12V_MEM_CPU0")
		)
		(pad "2" smd rect
			(at -0.889 0)
			(size 1.016 1.27)
			(layers "B.Cu" "B.Mask" "B.Paste")
			(net "GND")
		)
	)
	(footprint ""
		(layer "B.Cu")
		(at 278.671782 -346.784168 90)
		(property "Reference" "PC185_4"
			(at 0 0 90)
			(layer "B.SilkS")
			(hide yes)
			(effects
				(font
					(size 1.27 1.27)
				)
				(justify mirror)
			)
		)
		(property "Value" ""
			(at 0 0 90)
			(layer "B.Fab")
			(effects
				(font
					(size 1.27 1.27)
				)
				(justify mirror)
			)
		)
		(duplicate_pad_numbers_are_jumpers no)
		(fp_line
			(start 1.524 -0.762)
			(end -1.524 -0.762)
			(stroke
				(width 0.1524)
				(type default)
			)
			(layer "B.SilkS")
		)
		(fp_line
			(start -1.524 -0.762)
			(end -1.524 0.762)
			(stroke
				(width 0.1524)
				(type default)
			)
			(layer "B.SilkS")
		)
		(fp_line
			(start 1.524 0.762)
			(end 1.524 -0.762)
			(stroke
				(width 0.1524)
				(type default)
			)
			(layer "B.SilkS")
		)
		(fp_line
			(start -1.524 0.762)
			(end 1.524 0.762)
			(stroke
				(width 0.1524)
				(type default)
			)
			(layer "B.SilkS")
		)
		(fp_line
			(start 1.1049 -0.724916)
			(end 1.1049 0.724916)
			(stroke
				(width 0.1)
				(type default)
			)
			(layer "B.Fab")
		)
		(fp_line
			(start -1.1049 -0.724916)
			(end 1.1049 -0.724916)
			(stroke
				(width 0.1)
				(type default)
			)
			(layer "B.Fab")
		)
		(fp_line
			(start 1.1049 0.724916)
			(end -1.1049 0.724916)
			(stroke
				(width 0.1)
				(type default)
			)
			(layer "B.Fab")
		)
		(fp_line
			(start -1.1049 0.724916)
			(end -1.1049 -0.724916)
			(stroke
				(width 0.1)
				(type default)
			)
			(layer "B.Fab")
		)
		(pad "1" smd rect
			(at 0.889 0 90)
			(size 1.016 1.27)
			(layers "B.Cu" "B.Mask" "B.Paste")
			(net "SW_P12V_AUX_PVDDIO_P0_FLT")
		)
		(pad "2" smd rect
			(at -0.889 0 90)
			(size 1.016 1.27)
			(layers "B.Cu" "B.Mask" "B.Paste")
			(net "GND")
		)
	)
)
